(kicad_pcb
	(version 20260206)
	(generator "pcbnew")
	(generator_version "10.0")
	(general
		(thickness 1.6)
		(legacy_teardrops no)
	)
	(paper "A4")
	(title_block
		(title "03242023_DA0F0TMBIJ0_F0T_Motherboard_J_brd_V01_OCP.brd")
		(comment 1 "Grand Teton / footprints 3036-3038 of 6105")
	)
	(layers
		(0 "F.Cu" signal "TOP")
		(4 "In1.Cu" signal "GND")
		(6 "In2.Cu" signal "IN1")
		(8 "In3.Cu" signal "GND1")
		(10 "In4.Cu" signal "IN2")
		(12 "In5.Cu" signal "GND2")
		(14 "In6.Cu" signal "IN3")
		(16 "In7.Cu" signal "GND3")
		(18 "In8.Cu" signal "VCC")
		(20 "In9.Cu" signal "VCC1")
		(22 "In10.Cu" signal "GND4")
		(24 "In11.Cu" signal "IN4")
		(26 "In12.Cu" signal "GND5")
		(28 "In13.Cu" signal "IN5")
		(30 "In14.Cu" signal "GND6")
		(32 "In15.Cu" signal "IN6")
		(34 "In16.Cu" signal "GND7")
		(2 "B.Cu" signal "BOTTOM")
		(9 "F.Adhes" user "F.Adhesive")
		(11 "B.Adhes" user "B.Adhesive")
		(13 "F.Paste" user "Package Geometry/Pastemask Top")
		(15 "B.Paste" user "Package Geometry/Pastemask Bottom")
		(5 "F.SilkS" user "Ref Des/Silkscreen Top")
		(7 "B.SilkS" user "Ref Des/Silkscreen Bottom")
		(1 "F.Mask" user "Board Geometry/Soldermask Top")
		(3 "B.Mask" user "Board Geometry/Soldermask Bottom")
		(17 "Dwgs.User" user "User.Drawings")
		(19 "Cmts.User" user "User.Comments")
		(21 "Eco1.User" user "User.Eco1")
		(23 "Eco2.User" user "User.Eco2")
		(25 "Edge.Cuts" user "Board Geometry/Outline")
		(27 "Margin" user)
		(31 "F.CrtYd" user "Package Geometry/Place Bound Top")
		(29 "B.CrtYd" user "Package Geometry/Place Bound Bottom")
		(35 "F.Fab" user "Ref Des/Assembly Top")
		(33 "B.Fab" user "Ref Des/Assembly Bottom")
	)
	(footprint ""
		(layer "F.Cu")
		(at 366.48263 -245.634002 -90)
		(property "Reference" "C1005"
			(at 0 0 270)
			(layer "F.SilkS")
			(hide yes)
			(effects
				(font
					(size 1.27 1.27)
				)
			)
		)
		(property "Value" ""
			(at 0 0 270)
			(layer "F.Fab")
			(effects
				(font
					(size 1.27 1.27)
				)
			)
		)
		(duplicate_pad_numbers_are_jumpers no)
		(fp_line
			(start -0.7874 0.4064)
			(end -0.7874 -0.4064)
			(stroke
				(width 0.1524)
				(type default)
			)
			(layer "F.SilkS")
		)
		(fp_line
			(start 0.7874 0.4064)
			(end -0.7874 0.4064)
			(stroke
				(width 0.1524)
				(type default)
			)
			(layer "F.SilkS")
		)
		(fp_line
			(start -0.7874 -0.4064)
			(end 0.7874 -0.4064)
			(stroke
				(width 0.1524)
				(type default)
			)
			(layer "F.SilkS")
		)
		(fp_line
			(start 0.7874 -0.4064)
			(end 0.7874 0.4064)
			(stroke
				(width 0.1524)
				(type default)
			)
			(layer "F.SilkS")
		)
		(fp_line
			(start -0.67945 0.3048)
			(end -0.67945 -0.305054)
			(stroke
				(width 0.1)
				(type default)
			)
			(layer "F.Fab")
		)
		(fp_line
			(start -0.12065 0.3048)
			(end -0.67945 0.3048)
			(stroke
				(width 0.1)
				(type default)
			)
			(layer "F.Fab")
		)
		(fp_line
			(start 0.120396 0.3048)
			(end 0.120396 0.2794)
			(stroke
				(width 0.1)
				(type default)
			)
			(layer "F.Fab")
		)
		(fp_line
			(start 0.67945 0.3048)
			(end 0.120396 0.3048)
			(stroke
				(width 0.1)
				(type default)
			)
			(layer "F.Fab")
		)
		(fp_line
			(start -0.12065 0.2794)
			(end -0.12065 0.3048)
			(stroke
				(width 0.1)
				(type default)
			)
			(layer "F.Fab")
		)
		(fp_line
			(start 0.120396 0.2794)
			(end -0.12065 0.2794)
			(stroke
				(width 0.1)
				(type default)
			)
			(layer "F.Fab")
		)
		(fp_line
			(start -0.12065 -0.2794)
			(end 0.12065 -0.2794)
			(stroke
				(width 0.1)
				(type default)
			)
			(layer "F.Fab")
		)
		(fp_line
			(start 0.12065 -0.2794)
			(end 0.12065 -0.3048)
			(stroke
				(width 0.1)
				(type default)
			)
			(layer "F.Fab")
		)
		(fp_line
			(start 0.12065 -0.3048)
			(end 0.67945 -0.3048)
			(stroke
				(width 0.1)
				(type default)
			)
			(layer "F.Fab")
		)
		(fp_line
			(start 0.67945 -0.3048)
			(end 0.67945 0.3048)
			(stroke
				(width 0.1)
				(type default)
			)
			(layer "F.Fab")
		)
		(fp_line
			(start -0.67945 -0.305054)
			(end -0.12065 -0.305054)
			(stroke
				(width 0.1)
				(type default)
			)
			(layer "F.Fab")
		)
		(fp_line
			(start -0.12065 -0.305054)
			(end -0.12065 -0.2794)
			(stroke
				(width 0.1)
				(type default)
			)
			(layer "F.Fab")
		)
		(pad "1" smd circle
			(at -0.40005 0 270)
			(size 0 0)
			(layers "F.Cu" "F.Mask" "F.Paste")
			(net "PVCCIN_CPU0")
		)
		(pad "2" smd circle
			(at 0.40005 0 270)
			(size 0 0)
			(layers "F.Cu" "F.Mask" "F.Paste")
			(net "GND")
		)
	)
	(footprint ""
		(layer "F.Cu")
		(at 333.335884 -343.496138 -90)
		(property "Reference" "PC231_P0_7"
			(at 0 0 270)
			(layer "F.SilkS")
			(hide yes)
			(effects
				(font
					(size 1.27 1.27)
				)
			)
		)
		(property "Value" ""
			(at 0 0 270)
			(layer "F.Fab")
			(effects
				(font
					(size 1.27 1.27)
				)
			)
		)
		(duplicate_pad_numbers_are_jumpers no)
		(fp_line
			(start -0.7874 0.4064)
			(end -0.7874 -0.4064)
			(stroke
				(width 0.1524)
				(type default)
			)
			(layer "F.SilkS")
		)
		(fp_line
			(start 0.7874 0.4064)
			(end -0.7874 0.4064)
			(stroke
				(width 0.1524)
				(type default)
			)
			(layer "F.SilkS")
		)
		(fp_line
			(start -0.7874 -0.4064)
			(end 0.7874 -0.4064)
			(stroke
				(width 0.1524)
				(type default)
			)
			(layer "F.SilkS")
		)
		(fp_line
			(start 0.7874 -0.4064)
			(end 0.7874 0.4064)
			(stroke
				(width 0.1524)
				(type default)
			)
			(layer "F.SilkS")
		)
		(fp_line
			(start -0.67945 0.3048)
			(end -0.67945 -0.305054)
			(stroke
				(width 0.1)
				(type default)
			)
			(layer "F.Fab")
		)
		(fp_line
			(start -0.12065 0.3048)
			(end -0.67945 0.3048)
			(stroke
				(width 0.1)
				(type default)
			)
			(layer "F.Fab")
		)
		(fp_line
			(start 0.120396 0.3048)
			(end 0.120396 0.2794)
			(stroke
				(width 0.1)
				(type default)
			)
			(layer "F.Fab")
		)
		(fp_line
			(start 0.67945 0.3048)
			(end 0.120396 0.3048)
			(stroke
				(width 0.1)
				(type default)
			)
			(layer "F.Fab")
		)
		(fp_line
			(start -0.12065 0.2794)
			(end -0.12065 0.3048)
			(stroke
				(width 0.1)
				(type default)
			)
			(layer "F.Fab")
		)
		(fp_line
			(start 0.120396 0.2794)
			(end -0.12065 0.2794)
			(stroke
				(width 0.1)
				(type default)
			)
			(layer "F.Fab")
		)
		(fp_line
			(start -0.12065 -0.2794)
			(end 0.12065 -0.2794)
			(stroke
				(width 0.1)
				(type default)
			)
			(layer "F.Fab")
		)
		(fp_line
			(start 0.12065 -0.2794)
			(end 0.12065 -0.3048)
			(stroke
				(width 0.1)
				(type default)
			)
			(layer "F.Fab")
		)
		(fp_line
			(start 0.12065 -0.3048)
			(end 0.67945 -0.3048)
			(stroke
				(width 0.1)
				(type default)
			)
			(layer "F.Fab")
		)
		(fp_line
			(start 0.67945 -0.3048)
			(end 0.67945 0.3048)
			(stroke
				(width 0.1)
				(type default)
			)
			(layer "F.Fab")
		)
		(fp_line
			(start -0.67945 -0.305054)
			(end -0.12065 -0.305054)
			(stroke
				(width 0.1)
				(type default)
			)
			(layer "F.Fab")
		)
		(fp_line
			(start -0.12065 -0.305054)
			(end -0.12065 -0.2794)
			(stroke
				(width 0.1)
				(type default)
			)
			(layer "F.Fab")
		)
		(pad "1" smd circle
			(at -0.40005 0 270)
			(size 0 0)
			(layers "F.Cu" "F.Mask" "F.Paste")
			(net "SW_P12V_PVCCIN_CPU0_FLT")
		)
		(pad "2" smd circle
			(at 0.40005 0 270)
			(size 0 0)
			(layers "F.Cu" "F.Mask" "F.Paste")
			(net "GND")
		)
	)
	(footprint ""
		(layer "F.Cu")
		(at 81.435956 -347.520514 90)
		(property "Reference" "PR1793"
			(at 0 0 90)
			(layer "F.SilkS")
			(hide yes)
			(effects
				(font
					(size 1.27 1.27)
				)
			)
		)
		(property "Value" ""
			(at 0 0 90)
			(layer "F.Fab")
			(effects
				(font
					(size 1.27 1.27)
				)
			)
		)
		(duplicate_pad_numbers_are_jumpers no)
		(fp_line
			(start 0.7874 -0.4064)
			(end 0.7874 0.4064)
			(stroke
				(width 0.1524)
				(type default)
			)
			(layer "F.SilkS")
		)
		(fp_line
			(start -0.7874 -0.4064)
			(end 0.7874 -0.4064)
			(stroke
				(width 0.1524)
				(type default)
			)
			(layer "F.SilkS")
		)
		(fp_line
			(start 0.7874 0.4064)
			(end -0.7874 0.4064)
			(stroke
				(width 0.1524)
				(type default)
			)
			(layer "F.SilkS")
		)
		(fp_line
			(start -0.7874 0.4064)
			(end -0.7874 -0.4064)
			(stroke
				(width 0.1524)
				(type default)
			)
			(layer "F.SilkS")
		)
		(fp_line
			(start -0.12065 -0.305054)
			(end -0.12065 -0.2794)
			(stroke
				(width 0.1)
				(type default)
			)
			(layer "F.Fab")
		)
		(fp_line
			(start -0.67945 -0.305054)
			(end -0.12065 -0.305054)
			(stroke
				(width 0.1)
				(type default)
			)
			(layer "F.Fab")
		)
		(fp_line
			(start 0.67945 -0.3048)
			(end 0.67945 0.3048)
			(stroke
				(width 0.1)
				(type default)
			)
			(layer "F.Fab")
		)
		(fp_line
			(start 0.12065 -0.3048)
			(end 0.67945 -0.3048)
			(stroke
				(width 0.1)
				(type default)
			)
			(layer "F.Fab")
		)
		(fp_line
			(start 0.12065 -0.2794)
			(end 0.12065 -0.3048)
			(stroke
				(width 0.1)
				(type default)
			)
			(layer "F.Fab")
		)
		(fp_line
			(start -0.12065 -0.2794)
			(end 0.12065 -0.2794)
			(stroke
				(width 0.1)
				(type default)
			)
			(layer "F.Fab")
		)
		(fp_line
			(start 0.120396 0.2794)
			(end -0.12065 0.2794)
			(stroke
				(width 0.1)
				(type default)
			)
			(layer "F.Fab")
		)
		(fp_line
			(start -0.12065 0.2794)
			(end -0.12065 0.3048)
			(stroke
				(width 0.1)
				(type default)
			)
			(layer "F.Fab")
		)
		(fp_line
			(start 0.67945 0.3048)
			(end 0.120396 0.3048)
			(stroke
				(width 0.1)
				(type default)
			)
			(layer "F.Fab")
		)
		(fp_line
			(start 0.120396 0.3048)
			(end 0.120396 0.2794)
			(stroke
				(width 0.1)
				(type default)
			)
			(layer "F.Fab")
		)
		(fp_line
			(start -0.12065 0.3048)
			(end -0.67945 0.3048)
			(stroke
				(width 0.1)
				(type default)
			)
			(layer "F.Fab")
		)
		(fp_line
			(start -0.67945 0.3048)
			(end -0.67945 -0.305054)
			(stroke
				(width 0.1)
				(type default)
			)
			(layer "F.Fab")
		)
		(pad "1" smd circle
			(at -0.40005 0 90)
			(size 0 0)
			(layers "F.Cu" "F.Mask" "F.Paste")
			(net "SW_PVCCIN_CPU1_BOOT7")
		)
		(pad "2" smd circle
			(at 0.40005 0 90)
			(size 0 0)
			(layers "F.Cu" "F.Mask" "F.Paste")
			(net "SW_PVCCIN_CPU1_BOOT7_R")
		)
	)
)
